G04 ================== begin FILE IDENTIFICATION RECORD ==================*
G04 Layout Name:  13919-sa.brd*
G04 Film Name:    L2VCC*
G04 File Format:  Gerber RS274X*
G04 File Origin:  Cadence Allegro 16.5-S039*
G04 Origin Date:  Fri Nov 22 15:27:05 2013*
G04 *
G04 Layer:  VIA CLASS/L2VCC*
G04 Layer:  PIN/L2VCC*
G04 Layer:  PACKAGE GEOMETRY/PWRVCC*
G04 Layer:  ETCH/L2VCC*
G04 Layer:  DRAWING FORMAT/LAYER_L2VCC*
G04 Layer:  DRAWING FORMAT/LAYER_PCB_STORY*
G04 *
G04 Offset:    (0.00 0.00)*
G04 Mirror:    No*
G04 Mode:      Negative*
G04 Rotation:  0*
G04 FullContactRelief:  No*
G04 UndefLineWidth:     6.00*
G04 ================== end FILE IDENTIFICATION RECORD ====================*
%FSLAX35Y35*MOIN*%
%IR0*IPPOS*OFA0.00000B0.00000*MIA0B0*SFA1.00000B1.00000*%
%ADD15C,.032*%
%ADD13C,.057*%
%AMMACRO10*
4,1,15,.00398,.00044,
.003999,.000208,
.004004,-.000025,
.003996,-.000258,
.00398,-.00044,
.00483,-.00129,
.004897,-.001007,
.004947,-.000721,
.004981,-.000432,
.004997,-.000141,
.004997,.000149,
.00498,.00044,
.004946,.000729,
.004895,.001015,
.00483,.00129,
.00398,.00044,
0.0*
4,1,15,.00044,-.00398,
.000208,-.003999,
-.000025,-.004004,
-.000258,-.003996,
-.00044,-.00398,
-.00129,-.00483,
-.001007,-.004897,
-.000721,-.004947,
-.000432,-.004981,
-.000141,-.004997,
.000149,-.004997,
.00044,-.00498,
.000729,-.004946,
.001015,-.004895,
.00129,-.00483,
.00044,-.00398,
0.0*
4,1,15,-.00398,-.00044,
-.003999,-.000208,
-.004004,.000025,
-.003996,.000258,
-.00398,.00044,
-.00483,.00129,
-.004897,.001007,
-.004947,.000721,
-.004981,.000432,
-.004997,.000141,
-.004997,-.000149,
-.00498,-.00044,
-.004946,-.000729,
-.004895,-.001015,
-.00483,-.00129,
-.00398,-.00044,
0.0*
4,1,15,-.00044,.00398,
-.000208,.003999,
.000025,.004004,
.000258,.003996,
.00044,.00398,
.00129,.00483,
.001007,.004897,
.000721,.004947,
.000432,.004981,
.000141,.004997,
-.000149,.004997,
-.00044,.00498,
-.000729,.004946,
-.001015,.004895,
-.00129,.00483,
-.00044,.00398,
0.0*
%
%ADD10MACRO10*%
%AMMACRO12*
4,1,19,.02211,.00797,
.022536,.006671,
.022886,.005349,
.023158,.00401,
.023352,.002656,
.023467,.001294,
.023503,-.000073,
.023459,-.001439,
.023335,-.002801,
.023133,-.004153,
.022852,-.005491,
.022494,-.00681,
.02211,-.00797,
.02594,-.0118,
.027595,-.007116,
.028411,-.002216,
.028365,.002751,
.027456,.007635,
.02594,.0118,
.02211,.00797,
180.*
4,1,19,.00797,-.02211,
.006671,-.022536,
.005349,-.022886,
.00401,-.023158,
.002656,-.023352,
.001294,-.023467,
-.000073,-.023503,
-.001439,-.023459,
-.002801,-.023335,
-.004153,-.023133,
-.005491,-.022852,
-.00681,-.022494,
-.00797,-.02211,
-.0118,-.02594,
-.007116,-.027595,
-.002216,-.028411,
.002751,-.028365,
.007635,-.027456,
.0118,-.02594,
.00797,-.02211,
180.*
4,1,19,-.02211,-.00797,
-.022536,-.006671,
-.022886,-.005349,
-.023158,-.00401,
-.023352,-.002656,
-.023467,-.001294,
-.023503,.000073,
-.023459,.001439,
-.023335,.002801,
-.023133,.004153,
-.022852,.005491,
-.022494,.00681,
-.02211,.00797,
-.02594,.0118,
-.027595,.007116,
-.028411,.002216,
-.028365,-.002751,
-.027456,-.007635,
-.02594,-.0118,
-.02211,-.00797,
180.*
4,1,19,-.00797,.02211,
-.006671,.022536,
-.005349,.022886,
-.00401,.023158,
-.002656,.023352,
-.001294,.023467,
.000073,.023503,
.001439,.023459,
.002801,.023335,
.004153,.023133,
.005491,.022852,
.00681,.022494,
.00797,.02211,
.0118,.02594,
.007116,.027595,
.002216,.028411,
-.002751,.028365,
-.007635,.027456,
-.0118,.02594,
-.00797,.02211,
180.*
%
%ADD12MACRO12*%
%ADD11C,.121*%
%ADD14C,.114*%
%ADD16C,.02*%
%ADD17C,.006*%
%ADD18C,.11004*%
%ADD19C,.11704*%
G75*
%LPD*%
G75*
G36*
G01X-6000Y-6000D02*
X380016D01*
Y112693D01*
X-6000D01*
Y-6000D01*
G37*
%LPC*%
G75*
G36*
G01X308108Y35989D02*
G02X307563Y35616I-400J0D01*
G03X298529Y30771I-2445J-6285D01*
G01Y30770D01*
X298516Y30712D01*
X298378Y30574D01*
Y29554D01*
G03X298374Y29331I6740J-232D01*
G01Y22000D01*
X24067D01*
Y29922D01*
G03X24063Y30148I-6941J-10D01*
G01Y31164D01*
X23929Y31297D01*
X23917Y31355D01*
G03X23876Y31538I-6793J-1426D01*
G01X23850Y31647D01*
X36183Y43980D01*
Y66989D01*
X40183Y70989D01*
Y75489D01*
X41544Y76850D01*
X298871D01*
G03X310185I5657J1496D01*
G01X312232D01*
X313983Y75099D01*
Y71611D01*
X313362Y70989D01*
X310077Y67705D01*
Y60395D01*
X309914Y60364D01*
G03X305890Y55515I913J-4852D01*
G01Y43287D01*
X305909Y43268D01*
X305916Y43198D01*
G03X308081Y39598I4911J503D01*
G01X308097Y39587D01*
X308253Y39432D01*
X308108Y39287D01*
Y35989D01*
G37*
G36*
G01X309608Y38665D02*
X309811Y38868D01*
X309915Y38849D01*
G03X310394Y38783I913J4852D01*
G01X310435Y38779D01*
X310464Y38764D01*
X323052D01*
X323070Y38782D01*
X323141Y38790D01*
G03X327549Y43198I-503J4911D01*
G01X327557Y43269D01*
X327575Y43287D01*
Y55926D01*
X327557Y55944D01*
X327549Y56015D01*
G03X323141Y60423I-4911J-503D01*
G01X323070Y60431D01*
X323052Y60449D01*
X311577D01*
Y67083D01*
X315483Y70989D01*
Y75721D01*
X312854Y78350D01*
X310383D01*
X310376Y78543D01*
G03X298680I-5848J-197D01*
G01X298673Y78350D01*
X40922D01*
X38683Y76111D01*
Y71611D01*
X34683Y67611D01*
Y44602D01*
X23625Y33543D01*
G02X23004Y33613I-283J283D01*
G03X18560Y36712I-5877J-3692D01*
G01X18502Y36724D01*
X18369Y36858D01*
X17359D01*
G03X17127Y36862I-236J-6937D01*
G01X3937D01*
G02X3004Y37795I0J933D01*
G01Y48361D01*
G02X3766Y48530I400J-1D01*
G03Y53190I4984J2330D01*
G02X3004Y53359I-362J170D01*
G01Y102756D01*
G02X3937Y103689I933J0D01*
G01X143701D01*
G02X144634Y102756I0J-933D01*
G03X150141Y95965I6941J0D01*
G01X150199Y95953D01*
X150332Y95819D01*
X151342D01*
G03X151574Y95815I236J6937D01*
G01X222442D01*
G03X222674Y95819I-4J6941D01*
G01X223684D01*
X223817Y95953D01*
X223875Y95965D01*
G03X229382Y102756I-1434J6791D01*
G02X230315Y103689I933J0D01*
G01X370079D01*
G02X371012Y102756I0J-933D01*
G01Y67815D01*
G02X370079Y66882I-933J0D01*
G01X356889D01*
G03X356657Y66878I4J-6941D01*
G01X355647D01*
X355514Y66744D01*
X355456Y66732D01*
G03X350099Y61375I1434J-6791D01*
G01X350087Y61317D01*
X349953Y61184D01*
Y60174D01*
G03X349949Y59942I6937J-236D01*
G01Y22000D01*
X311862D01*
Y29331D01*
G03X311858Y29560I-6744J-3D01*
G01Y30574D01*
X311719Y30713D01*
X311707Y30770D01*
G03X309608Y34363I-6589J-1439D01*
G01Y38665D01*
G37*
%LPD*%
G75*
G36*
G01X279923Y43269D02*
X279905Y43287D01*
Y55926D01*
X279923Y55944D01*
X279931Y56015D01*
G02X284339Y60423I4911J-503D01*
G01X284410Y60431D01*
X284428Y60449D01*
X297067D01*
X297085Y60431D01*
X297156Y60423D01*
G02X301590Y55524I-503J-4911D01*
G01Y43287D01*
X301572Y43269D01*
X301564Y43198D01*
G02X297156Y38790I-4911J503D01*
G01X297085Y38782D01*
X297067Y38764D01*
X284428D01*
X284410Y38782D01*
X284339Y38790D01*
G02X279931Y43198I503J4911D01*
G01X279923Y43269D01*
G37*
G36*
G01X275580Y56015D02*
X275588Y55944D01*
X275606Y55926D01*
Y43287D01*
X275588Y43269D01*
X275580Y43198D01*
G02X271172Y38790I-4911J503D01*
G01X271101Y38782D01*
X271083Y38764D01*
X258444D01*
X258426Y38782D01*
X258355Y38790D01*
G02X253947Y43198I503J4911D01*
G01X253939Y43269D01*
X253921Y43287D01*
Y55926D01*
X253939Y55944D01*
X253947Y56015D01*
G02X258355Y60423I4911J-503D01*
G01X258426Y60431D01*
X258444Y60449D01*
X271083D01*
X271101Y60431D01*
X271172Y60423D01*
G02X275580Y56015I-503J-4911D01*
G37*
G54D18*
X8950Y97440D03*
X364570Y96910D03*
G54D19*
X16538Y78346D03*
G54D15*
X329633Y31100D03*
X338583Y32050D03*
G54D13*
X43308Y73426D03*
X39373Y65551D03*
X35433Y73426D03*
X31498Y65551D03*
X47243Y91141D03*
X43308Y83266D03*
X39373Y91141D03*
X35433Y83266D03*
X31498Y91141D03*
X27558Y83266D03*
X23623Y91141D03*
X106298Y73426D03*
X102363Y65551D03*
X90553Y73426D03*
X86613Y65551D03*
X74803Y73426D03*
X70868Y65551D03*
X59058Y73426D03*
X55118Y65551D03*
X110238Y91141D03*
X106298Y83266D03*
X102363Y91141D03*
X98428Y83266D03*
X94488Y91141D03*
X90553Y83266D03*
X86613Y91141D03*
X82678Y83266D03*
X78743Y91141D03*
X74803Y83266D03*
X70868Y91141D03*
X66928Y83266D03*
X62993Y91141D03*
X59058Y83266D03*
X55118Y91141D03*
X51183Y83266D03*
X169293Y73426D03*
X165353Y65551D03*
X153543Y73426D03*
X149608Y65551D03*
X137798Y73426D03*
X133858Y65551D03*
X122048Y73426D03*
X118113Y65551D03*
X169293Y83266D03*
X165353Y91141D03*
X161418Y83266D03*
X157483Y91141D03*
X153543Y83266D03*
X149608Y91141D03*
X145668Y83266D03*
X141733Y91141D03*
X137798Y83266D03*
X133858Y91141D03*
X129923Y83266D03*
X125983Y91141D03*
X122048Y83266D03*
X118113Y91141D03*
X114173Y83266D03*
X232283Y73426D03*
X228348Y65551D03*
X216538Y73426D03*
X212598Y65551D03*
X200788Y73426D03*
X196853Y65551D03*
X185038Y73426D03*
X181103Y65551D03*
X232283Y83266D03*
X228348Y91141D03*
X224408Y83266D03*
X220473Y91141D03*
X216538Y83266D03*
X212598Y91141D03*
X208663Y83266D03*
X204723Y91141D03*
X200788Y83266D03*
X196853Y91141D03*
X192913Y83266D03*
X188978Y91141D03*
X185038Y83266D03*
X181103Y91141D03*
X177168Y83266D03*
X173228Y91141D03*
X291338Y65551D03*
X279528Y73426D03*
X275593Y65551D03*
X263778Y73426D03*
X259843Y65551D03*
X248033Y73426D03*
X244093Y65551D03*
X291338Y91141D03*
X287403Y83266D03*
X283463Y91141D03*
X279528Y83266D03*
X275593Y91141D03*
X271653Y83266D03*
X267718Y91141D03*
X263778Y83266D03*
X259843Y91141D03*
X255908Y83266D03*
X251968Y91141D03*
X248033Y83266D03*
X244093Y91141D03*
X240158Y83266D03*
X236223Y91141D03*
X350393Y73426D03*
X338583Y65551D03*
X334648Y73426D03*
X330708Y65551D03*
X326773Y73426D03*
X322833Y65551D03*
X318898Y73426D03*
X314963Y65551D03*
X311023Y73426D03*
X295278D03*
X338583Y91141D03*
X334648Y83266D03*
X330708Y91141D03*
X326773Y83266D03*
X322833Y91141D03*
X318898Y83266D03*
X314963Y91141D03*
X311023Y83266D03*
X299213Y91141D03*
X295278Y83266D03*
G54D10*
X45633Y31600D03*
X38133Y31500D03*
X35363Y37960D03*
X30680Y42700D03*
X23720Y37880D03*
X30833Y58700D03*
X21533Y59100D03*
X17033Y53450D03*
X15633Y69500D03*
X25733Y53450D03*
X15333Y62700D03*
X108333Y31600D03*
X100733Y31500D03*
X92533D03*
X84233Y31400D03*
X77233Y31700D03*
X68633Y31400D03*
X60633Y31500D03*
X52733Y31400D03*
X163733Y31500D03*
X155433Y31600D03*
X147833Y31500D03*
X139733D03*
X132333Y31600D03*
X124233D03*
X116233Y31500D03*
X226933D03*
X219033Y31600D03*
X210633Y31500D03*
X202433Y31400D03*
X194933Y31600D03*
X188976Y31543D03*
X179133Y31600D03*
X171333D03*
X288533Y31020D03*
X280933Y31400D03*
X274433D03*
X266033Y31020D03*
X258233Y31300D03*
X249533Y31400D03*
X242333Y31600D03*
X234333Y31400D03*
X295275Y31658D03*
X343019Y32504D03*
X347544Y32400D03*
X344360Y43670D03*
X343700Y53890D03*
X340080Y47960D03*
X340010Y58570D03*
X354650Y89890D03*
X355770Y78680D03*
X357350Y72160D03*
G54D12*
X47243Y65551D03*
X27558Y73426D03*
X23623Y65551D03*
X110238D03*
X98428Y73426D03*
X94488Y65551D03*
X82678Y73426D03*
X78743Y65551D03*
X66928Y73426D03*
X62993Y65551D03*
X51183Y73426D03*
X161418D03*
X157483Y65551D03*
X145668Y73426D03*
X141733Y65551D03*
X129923Y73426D03*
X125983Y65551D03*
X114173Y73426D03*
X224408D03*
X220473Y65551D03*
X208663Y73426D03*
X204723Y65551D03*
X192913Y73426D03*
X188978Y65551D03*
X177168Y73426D03*
X173228Y65551D03*
X287403Y73426D03*
X283463Y65551D03*
X271653Y73426D03*
X267718Y65551D03*
X255908Y73426D03*
X251968Y65551D03*
X240158Y73426D03*
X236223Y65551D03*
X346458D03*
X342518Y73426D03*
X299213Y65551D03*
X350393Y83266D03*
X346458Y91141D03*
X342518Y83266D03*
G54D11*
X16538Y78346D03*
X304528D03*
G54D14*
X8950Y97440D03*
X8750Y50860D03*
X-2462Y651994D03*
X364570Y96910D03*
X758452Y17317D03*
X755722Y677788D03*
%LPC*%
G75*
G54D16*
G01X-67189Y-77263D02*
G02I-12000J0D01*
G01X-72339D02*
G02I-6850J0D01*
G01X-79189Y-93263D02*
Y-61263D01*
G01X-63189Y-77263D02*
X-95189D01*
G01X-63189Y-93263D02*
Y-173263D01*
G01D02*
X1156611D01*
G01X-63189Y-93263D02*
X1156611D01*
G01X-63189Y-128763D02*
X1156611D01*
G01X369111Y-93263D02*
Y-173263D01*
G01X506611Y-93263D02*
Y-173263D01*
G01X621611Y-93263D02*
Y-173263D01*
G01X789111Y-93263D02*
Y-173263D01*
G01X959111Y-93263D02*
Y-173263D01*
G01X1156611Y-93263D02*
Y-173263D01*
G01X1184611Y-77263D02*
G02I-12000J0D01*
G01X1179461D02*
G02I-6850J0D01*
G01X1172611Y-93263D02*
Y-61263D01*
G01X1188611Y-77263D02*
X1156611D01*
G54D17*
G01X-44374Y-163263D02*
Y-145763D01*
G01X-35204D02*
Y-163263D01*
G01Y-154513D02*
X-44374D01*
G01X-22289Y-163263D02*
X-23599Y-162971D01*
X-24909Y-161805D01*
X-25783Y-159763D01*
X-26219Y-157430D01*
X-25783Y-155096D01*
X-24909Y-153055D01*
X-23599Y-151888D01*
X-22289Y-151597D01*
X-20979Y-151888D01*
X-19669Y-153055D01*
X-18796Y-155096D01*
X-18577Y-157430D01*
X-18796Y-159763D01*
X-19669Y-161805D01*
X-20979Y-162971D01*
X-22289Y-163263D01*
G01X-8501D02*
Y-151597D01*
G01Y-154513D02*
X-7627Y-153055D01*
X-6317Y-151888D01*
X-4571Y-151597D01*
X-3043Y-151888D01*
X-1732Y-153055D01*
X-1077Y-155096D01*
Y-163263D01*
G01X9436Y-155388D02*
X16423D01*
X15768Y-153346D01*
X14676Y-152180D01*
X13148Y-151597D01*
X11619Y-151888D01*
X10309Y-152763D01*
X9436Y-154805D01*
X8999Y-156555D01*
Y-158305D01*
X9436Y-160055D01*
X10528Y-161805D01*
X11838Y-162971D01*
X13366Y-163263D01*
X14894Y-162680D01*
X16423Y-160930D01*
G01X25626Y-168513D02*
X26936Y-169096D01*
X28683Y-168513D01*
X29774Y-167347D01*
X30648Y-165888D01*
X31957Y-161222D01*
X34796Y-151597D01*
G01X27809D02*
X31957Y-161222D01*
G01X66957Y-153930D02*
X67831Y-153055D01*
X68486Y-151597D01*
X68923Y-149554D01*
X68486Y-147805D01*
X67613Y-146638D01*
X66084Y-145763D01*
X60189D01*
Y-163263D01*
X67394D01*
X68923Y-162097D01*
X69796Y-160346D01*
X70233Y-158305D01*
X69796Y-156263D01*
X68486Y-154513D01*
X66957Y-153930D01*
X60189D01*
G01X86641Y-163263D02*
Y-151597D01*
G01Y-153638D02*
X85768Y-152472D01*
X84457Y-151888D01*
X82929Y-151597D01*
X81401Y-152180D01*
X80091Y-153346D01*
X79217Y-155096D01*
X78781Y-157430D01*
X79217Y-159763D01*
X80091Y-161513D01*
X81401Y-162680D01*
X82929Y-163263D01*
X84457Y-162971D01*
X85768Y-162097D01*
X86641Y-160930D01*
G01X104141Y-145763D02*
Y-163263D01*
G01Y-160639D02*
X103268Y-162097D01*
X101957Y-162971D01*
X100429Y-163263D01*
X98683Y-162680D01*
X97373Y-161222D01*
X96499Y-159472D01*
X96281Y-157430D01*
X96499Y-155388D01*
X97373Y-153638D01*
X98683Y-152180D01*
X100429Y-151597D01*
X101957Y-151888D01*
X103049Y-152472D01*
X104141Y-153638D01*
G01X114654Y-167638D02*
X116183Y-168805D01*
X117929Y-169096D01*
X119457Y-168805D01*
X120768Y-167347D01*
X121641Y-165305D01*
Y-151597D01*
G01Y-153930D02*
X120768Y-152763D01*
X119457Y-151888D01*
X117929Y-151597D01*
X116183Y-152180D01*
X115091Y-153346D01*
X114217Y-155388D01*
X113781Y-157430D01*
X113999Y-159180D01*
X114873Y-161222D01*
X116183Y-162680D01*
X117929Y-163263D01*
X119239Y-162971D01*
X120768Y-161805D01*
X121641Y-160639D01*
G01X131936Y-155388D02*
X138923D01*
X138268Y-153346D01*
X137176Y-152180D01*
X135648Y-151597D01*
X134119Y-151888D01*
X132809Y-152763D01*
X131936Y-154805D01*
X131499Y-156555D01*
Y-158305D01*
X131936Y-160055D01*
X133028Y-161805D01*
X134338Y-162971D01*
X135866Y-163263D01*
X137394Y-162680D01*
X138923Y-160930D01*
G01X149654Y-163263D02*
Y-151597D01*
G01Y-153930D02*
X150746Y-152763D01*
X151838Y-151888D01*
X153366Y-151597D01*
X154457Y-151888D01*
X155768Y-152763D01*
G01X183344Y-163263D02*
Y-145763D01*
X188803D01*
X190549Y-146638D01*
X191641Y-147805D01*
X192078Y-150138D01*
X191641Y-152472D01*
X190331Y-153930D01*
X188803Y-154805D01*
X183344D01*
G01X188803D02*
X192078Y-163263D01*
G01X205211Y-151597D02*
Y-163263D01*
G01Y-146930D02*
X204774Y-146638D01*
Y-146055D01*
X205211Y-145763D01*
X205648Y-146055D01*
Y-146638D01*
X205211Y-146930D01*
G01X219436Y-161222D02*
X220528Y-162388D01*
X222056Y-163263D01*
X223366D01*
X224676Y-162680D01*
X225549Y-161805D01*
X225986Y-160639D01*
X225768Y-158888D01*
X224894Y-158013D01*
X220964Y-156263D01*
X220091Y-154221D01*
X220528Y-152763D01*
X221401Y-151888D01*
X222711Y-151597D01*
X224021Y-151888D01*
X225331Y-152763D01*
G01X236936Y-155388D02*
X243923D01*
X243268Y-153346D01*
X242176Y-152180D01*
X240648Y-151597D01*
X239119Y-151888D01*
X237809Y-152763D01*
X236936Y-154805D01*
X236499Y-156555D01*
Y-158305D01*
X236936Y-160055D01*
X238028Y-161805D01*
X239338Y-162971D01*
X240866Y-163263D01*
X242394Y-162680D01*
X243923Y-160930D01*
G01X254654Y-163263D02*
Y-151597D01*
G01Y-153930D02*
X255746Y-152763D01*
X256838Y-151888D01*
X258366Y-151597D01*
X259457Y-151888D01*
X260768Y-152763D01*
G01X297514Y-147222D02*
X296204Y-146346D01*
X294676Y-145763D01*
X292929D01*
X290964Y-146638D01*
X289436Y-148096D01*
X288344Y-149847D01*
X287471Y-152763D01*
X287252Y-155388D01*
X287689Y-158013D01*
X288344Y-159763D01*
X289654Y-161513D01*
X291183Y-162680D01*
X292711Y-163263D01*
X294239D01*
X295768Y-162680D01*
X297078Y-161805D01*
X298170Y-160639D01*
G01X314141Y-163263D02*
Y-151597D01*
G01Y-153638D02*
X313268Y-152472D01*
X311957Y-151888D01*
X310429Y-151597D01*
X308901Y-152180D01*
X307591Y-153346D01*
X306717Y-155096D01*
X306281Y-157430D01*
X306717Y-159763D01*
X307591Y-161513D01*
X308901Y-162680D01*
X310429Y-163263D01*
X311957Y-162971D01*
X313268Y-162097D01*
X314141Y-160930D01*
G01X324654Y-163263D02*
Y-151597D01*
G01Y-153930D02*
X325746Y-152763D01*
X326838Y-151888D01*
X328366Y-151597D01*
X329457Y-151888D01*
X330768Y-152763D01*
G01X349141Y-145763D02*
Y-163263D01*
G01Y-160639D02*
X348268Y-162097D01*
X346957Y-162971D01*
X345429Y-163263D01*
X343683Y-162680D01*
X342373Y-161222D01*
X341499Y-159472D01*
X341281Y-157430D01*
X341499Y-155388D01*
X342373Y-153638D01*
X343683Y-152180D01*
X345429Y-151597D01*
X346957Y-151888D01*
X348049Y-152472D01*
X349141Y-153638D01*
G01X112034Y-118263D02*
Y-100763D01*
X117711Y-115346D01*
X123388Y-100763D01*
Y-118263D01*
G01X135211D02*
X133901Y-117971D01*
X132591Y-116805D01*
X131717Y-114763D01*
X131281Y-112430D01*
X131717Y-110096D01*
X132591Y-108055D01*
X133901Y-106888D01*
X135211Y-106597D01*
X136521Y-106888D01*
X137831Y-108055D01*
X138704Y-110096D01*
X138923Y-112430D01*
X138704Y-114763D01*
X137831Y-116805D01*
X136521Y-117971D01*
X135211Y-118263D01*
G01X156641Y-100763D02*
Y-118263D01*
G01Y-115639D02*
X155768Y-117097D01*
X154457Y-117971D01*
X152929Y-118263D01*
X151183Y-117680D01*
X149873Y-116222D01*
X148999Y-114472D01*
X148781Y-112430D01*
X148999Y-110388D01*
X149873Y-108638D01*
X151183Y-107180D01*
X152929Y-106597D01*
X154457Y-106888D01*
X155549Y-107472D01*
X156641Y-108638D01*
G01X166936Y-110388D02*
X173923D01*
X173268Y-108346D01*
X172176Y-107180D01*
X170648Y-106597D01*
X169119Y-106888D01*
X167809Y-107763D01*
X166936Y-109805D01*
X166499Y-111555D01*
Y-113305D01*
X166936Y-115055D01*
X168028Y-116805D01*
X169338Y-117971D01*
X170866Y-118263D01*
X172394Y-117680D01*
X173923Y-115930D01*
G01X187711Y-118263D02*
Y-100763D01*
G01X402811Y-163263D02*
Y-145763D01*
X400191Y-149263D01*
G01Y-163263D02*
X405431D01*
G01X415508Y-159763D02*
X416817Y-161805D01*
X418564Y-162971D01*
X420529Y-163263D01*
X422276Y-162971D01*
X424023Y-161513D01*
X425114Y-159763D01*
X425333Y-158013D01*
X424896Y-155972D01*
X423368Y-154513D01*
X421839Y-153930D01*
X419874D01*
G01X421839D02*
X423149Y-153055D01*
X424241Y-151597D01*
X424678Y-149847D01*
X424241Y-148096D01*
X423149Y-146638D01*
X421184Y-145763D01*
X419219Y-146055D01*
X417254Y-147222D01*
G01X434099Y-161222D02*
X435628Y-162680D01*
X437374Y-163263D01*
X439121Y-162680D01*
X440649Y-160930D01*
X441741Y-158305D01*
X442178Y-155680D01*
Y-152472D01*
X441741Y-149847D01*
X440649Y-147513D01*
X439339Y-146346D01*
X437811Y-145763D01*
X436064Y-146346D01*
X434754Y-147513D01*
X433881Y-149263D01*
X433444Y-151597D01*
X433881Y-153638D01*
X434973Y-155680D01*
X436283Y-156847D01*
X437811Y-157138D01*
X439557Y-156555D01*
X440868Y-155096D01*
X442178Y-152472D01*
G01X455311Y-163263D02*
Y-145763D01*
X452691Y-149263D01*
G01Y-163263D02*
X457931D01*
G01X469099Y-161222D02*
X470628Y-162680D01*
X472374Y-163263D01*
X474121Y-162680D01*
X475649Y-160930D01*
X476741Y-158305D01*
X477178Y-155680D01*
Y-152472D01*
X476741Y-149847D01*
X475649Y-147513D01*
X474339Y-146346D01*
X472811Y-145763D01*
X471064Y-146346D01*
X469754Y-147513D01*
X468881Y-149263D01*
X468444Y-151597D01*
X468881Y-153638D01*
X469973Y-155680D01*
X471283Y-156847D01*
X472811Y-157138D01*
X474557Y-156555D01*
X475868Y-155096D01*
X477178Y-152472D01*
G01X389694Y-118263D02*
Y-100763D01*
X394934D01*
X396681Y-101638D01*
X397991Y-103680D01*
X398428Y-106013D01*
X397991Y-108346D01*
X396899Y-110096D01*
X394934Y-110972D01*
X389694D01*
G01X416364Y-102222D02*
X415054Y-101346D01*
X413526Y-100763D01*
X411779D01*
X409814Y-101638D01*
X408286Y-103096D01*
X407194Y-104847D01*
X406321Y-107763D01*
X406102Y-110388D01*
X406539Y-113013D01*
X407194Y-114763D01*
X408504Y-116513D01*
X410033Y-117680D01*
X411561Y-118263D01*
X413089D01*
X414618Y-117680D01*
X415928Y-116805D01*
X417020Y-115639D01*
G01X430807Y-108930D02*
X431681Y-108055D01*
X432336Y-106597D01*
X432773Y-104554D01*
X432336Y-102805D01*
X431463Y-101638D01*
X429934Y-100763D01*
X424039D01*
Y-118263D01*
X431244D01*
X432773Y-117097D01*
X433646Y-115346D01*
X434083Y-113305D01*
X433646Y-111263D01*
X432336Y-109513D01*
X430807Y-108930D01*
X424039D01*
G01X440011Y-124096D02*
X453111D01*
G01X459039Y-118263D02*
Y-100763D01*
X469083Y-118263D01*
Y-100763D01*
G01X481561Y-118263D02*
X479814Y-117971D01*
X478286Y-116805D01*
X476976Y-115055D01*
X476102Y-113013D01*
X475666Y-110680D01*
Y-108346D01*
X476102Y-106013D01*
X476976Y-103971D01*
X478286Y-102222D01*
X479814Y-101055D01*
X481561Y-100763D01*
X483307Y-101055D01*
X484836Y-102222D01*
X486146Y-103971D01*
X487020Y-106013D01*
X487456Y-108346D01*
Y-110680D01*
X487020Y-113013D01*
X486146Y-115055D01*
X484836Y-116805D01*
X483307Y-117971D01*
X481561Y-118263D01*
G01X532402Y-100763D02*
X537861Y-118263D01*
X543320Y-100763D01*
G01X559728Y-118263D02*
X550994D01*
Y-100763D01*
X559728D01*
G01X556234Y-109221D02*
X550994D01*
G01X568494Y-118263D02*
Y-100763D01*
X573953D01*
X575699Y-101638D01*
X576791Y-102805D01*
X577228Y-105138D01*
X576791Y-107472D01*
X575481Y-108930D01*
X573953Y-109805D01*
X568494D01*
G01X573953D02*
X577228Y-118263D01*
G01X590361Y-118846D02*
X589924Y-118555D01*
Y-117971D01*
X590361Y-117680D01*
X590798Y-117971D01*
Y-118555D01*
X590361Y-118846D01*
G01X550776Y-160930D02*
X552523Y-162388D01*
X554488Y-163263D01*
X556234D01*
X557981Y-162388D01*
X559291Y-160930D01*
X559946Y-158888D01*
X559509Y-156847D01*
X558418Y-155096D01*
X556453Y-153930D01*
X553833Y-153346D01*
X552304Y-152180D01*
X551649Y-150138D01*
X552086Y-148096D01*
X553178Y-146638D01*
X554706Y-145763D01*
X556234D01*
X557763Y-146346D01*
X559073Y-147805D01*
G01X567402Y-163263D02*
X572861Y-145763D01*
X578320Y-163263D01*
G01X576354Y-157138D02*
X569367D01*
G01X665944Y-145763D02*
Y-163263D01*
X674678D01*
G01X683663Y-148680D02*
X684973Y-146930D01*
X686501Y-146055D01*
X688248Y-145763D01*
X690431Y-146346D01*
X691959Y-147805D01*
X692396Y-149554D01*
X692178Y-151305D01*
X691304Y-152763D01*
X686938Y-155680D01*
X684973Y-157721D01*
X683663Y-160639D01*
X683226Y-163263D01*
X692396D01*
G01X699852Y-145763D02*
X705311Y-163263D01*
X710770Y-145763D01*
G01X727614Y-147222D02*
X726304Y-146346D01*
X724776Y-145763D01*
X723029D01*
X721064Y-146638D01*
X719536Y-148096D01*
X718444Y-149847D01*
X717571Y-152763D01*
X717352Y-155388D01*
X717789Y-158013D01*
X718444Y-159763D01*
X719754Y-161513D01*
X721283Y-162680D01*
X722811Y-163263D01*
X724339D01*
X725868Y-162680D01*
X727178Y-161805D01*
X728270Y-160639D01*
G01X745114Y-147222D02*
X743804Y-146346D01*
X742276Y-145763D01*
X740529D01*
X738564Y-146638D01*
X737036Y-148096D01*
X735944Y-149847D01*
X735071Y-152763D01*
X734852Y-155388D01*
X735289Y-158013D01*
X735944Y-159763D01*
X737254Y-161513D01*
X738783Y-162680D01*
X740311Y-163263D01*
X741839D01*
X743368Y-162680D01*
X744678Y-161805D01*
X745770Y-160639D01*
G01X665944Y-100763D02*
Y-118263D01*
X674678D01*
G01X691741D02*
Y-106597D01*
G01Y-108638D02*
X690868Y-107472D01*
X689557Y-106888D01*
X688029Y-106597D01*
X686501Y-107180D01*
X685191Y-108346D01*
X684317Y-110096D01*
X683881Y-112430D01*
X684317Y-114763D01*
X685191Y-116513D01*
X686501Y-117680D01*
X688029Y-118263D01*
X689557Y-117971D01*
X690868Y-117097D01*
X691741Y-115930D01*
G01X700726Y-123513D02*
X702036Y-124096D01*
X703783Y-123513D01*
X704874Y-122347D01*
X705748Y-120888D01*
X707057Y-116222D01*
X709896Y-106597D01*
G01X702909D02*
X707057Y-116222D01*
G01X719536Y-110388D02*
X726523D01*
X725868Y-108346D01*
X724776Y-107180D01*
X723248Y-106597D01*
X721719Y-106888D01*
X720409Y-107763D01*
X719536Y-109805D01*
X719099Y-111555D01*
Y-113305D01*
X719536Y-115055D01*
X720628Y-116805D01*
X721938Y-117971D01*
X723466Y-118263D01*
X724994Y-117680D01*
X726523Y-115930D01*
G01X737254Y-118263D02*
Y-106597D01*
G01Y-108930D02*
X738346Y-107763D01*
X739438Y-106888D01*
X740966Y-106597D01*
X742057Y-106888D01*
X743368Y-107763D01*
G01X808058Y-118263D02*
Y-100763D01*
X812424D01*
X814171Y-101638D01*
X815481Y-102805D01*
X816573Y-104554D01*
X817446Y-106597D01*
X817664Y-109513D01*
X817446Y-112430D01*
X816573Y-114472D01*
X815481Y-116222D01*
X814171Y-117388D01*
X812424Y-118263D01*
X808058D01*
G01X827086Y-110388D02*
X834073D01*
X833418Y-108346D01*
X832326Y-107180D01*
X830798Y-106597D01*
X829269Y-106888D01*
X827959Y-107763D01*
X827086Y-109805D01*
X826649Y-111555D01*
Y-113305D01*
X827086Y-115055D01*
X828178Y-116805D01*
X829488Y-117971D01*
X831016Y-118263D01*
X832544Y-117680D01*
X834073Y-115930D01*
G01X844586Y-116222D02*
X845678Y-117388D01*
X847206Y-118263D01*
X848516D01*
X849826Y-117680D01*
X850699Y-116805D01*
X851136Y-115639D01*
X850918Y-113888D01*
X850044Y-113013D01*
X846114Y-111263D01*
X845241Y-109221D01*
X845678Y-107763D01*
X846551Y-106888D01*
X847861Y-106597D01*
X849171Y-106888D01*
X850481Y-107763D01*
G01X865361Y-106597D02*
Y-118263D01*
G01Y-101930D02*
X864924Y-101638D01*
Y-101055D01*
X865361Y-100763D01*
X865798Y-101055D01*
Y-101638D01*
X865361Y-101930D01*
G01X879804Y-122638D02*
X881333Y-123805D01*
X883079Y-124096D01*
X884607Y-123805D01*
X885918Y-122347D01*
X886791Y-120305D01*
Y-106597D01*
G01Y-108930D02*
X885918Y-107763D01*
X884607Y-106888D01*
X883079Y-106597D01*
X881333Y-107180D01*
X880241Y-108346D01*
X879367Y-110388D01*
X878931Y-112430D01*
X879149Y-114180D01*
X880023Y-116222D01*
X881333Y-117680D01*
X883079Y-118263D01*
X884389Y-117971D01*
X885918Y-116805D01*
X886791Y-115639D01*
G01X896649Y-118263D02*
Y-106597D01*
G01Y-109513D02*
X897523Y-108055D01*
X898833Y-106888D01*
X900579Y-106597D01*
X902107Y-106888D01*
X903418Y-108055D01*
X904073Y-110096D01*
Y-118263D01*
G01X914586Y-110388D02*
X921573D01*
X920918Y-108346D01*
X919826Y-107180D01*
X918298Y-106597D01*
X916769Y-106888D01*
X915459Y-107763D01*
X914586Y-109805D01*
X914149Y-111555D01*
Y-113305D01*
X914586Y-115055D01*
X915678Y-116805D01*
X916988Y-117971D01*
X918516Y-118263D01*
X920044Y-117680D01*
X921573Y-115930D01*
G01X932304Y-118263D02*
Y-106597D01*
G01Y-108930D02*
X933396Y-107763D01*
X934488Y-106888D01*
X936016Y-106597D01*
X937107Y-106888D01*
X938418Y-107763D01*
G01X853991Y-145763D02*
X859231D01*
G01X856611D02*
Y-163263D01*
G01X853991D02*
X859231D01*
G01X868652Y-145763D02*
X874111Y-163263D01*
X879570Y-145763D01*
G01X891611Y-163263D02*
Y-155388D01*
X887244Y-145763D01*
G01X895978D02*
X891611Y-155388D01*
G01X979061Y-163263D02*
Y-145763D01*
X976441Y-149263D01*
G01Y-163263D02*
X981681D01*
G01X996561D02*
Y-145763D01*
X993941Y-149263D01*
G01Y-163263D02*
X999181D01*
G01X1010131Y-163846D02*
X1017991Y-145763D01*
G01X1027413Y-148680D02*
X1028723Y-146930D01*
X1030251Y-146055D01*
X1031998Y-145763D01*
X1034181Y-146346D01*
X1035709Y-147805D01*
X1036146Y-149554D01*
X1035928Y-151305D01*
X1035054Y-152763D01*
X1030688Y-155680D01*
X1028723Y-157721D01*
X1027413Y-160639D01*
X1026976Y-163263D01*
X1036146D01*
G01X1044913Y-148680D02*
X1046223Y-146930D01*
X1047751Y-146055D01*
X1049498Y-145763D01*
X1051681Y-146346D01*
X1053209Y-147805D01*
X1053646Y-149554D01*
X1053428Y-151305D01*
X1052554Y-152763D01*
X1048188Y-155680D01*
X1046223Y-157721D01*
X1044913Y-160639D01*
X1044476Y-163263D01*
X1053646D01*
G01X1062631Y-163846D02*
X1070491Y-145763D01*
G01X1079913Y-148680D02*
X1081223Y-146930D01*
X1082751Y-146055D01*
X1084498Y-145763D01*
X1086681Y-146346D01*
X1088209Y-147805D01*
X1088646Y-149554D01*
X1088428Y-151305D01*
X1087554Y-152763D01*
X1083188Y-155680D01*
X1081223Y-157721D01*
X1079913Y-160639D01*
X1079476Y-163263D01*
X1088646D01*
G01X1101561Y-145763D02*
X1099814Y-146346D01*
X1098504Y-147805D01*
X1097631Y-149554D01*
X1096976Y-151888D01*
X1096758Y-154513D01*
X1096976Y-157138D01*
X1097631Y-159472D01*
X1098504Y-161222D01*
X1099814Y-162680D01*
X1101561Y-163263D01*
X1103307Y-162680D01*
X1104618Y-161222D01*
X1105491Y-159472D01*
X1106146Y-157138D01*
X1106364Y-154513D01*
X1106146Y-151888D01*
X1105491Y-149554D01*
X1104618Y-147805D01*
X1103307Y-146346D01*
X1101561Y-145763D01*
G01X1119061Y-163263D02*
Y-145763D01*
X1116441Y-149263D01*
G01Y-163263D02*
X1121681D01*
G01X1131758Y-159763D02*
X1133067Y-161805D01*
X1134814Y-162971D01*
X1136779Y-163263D01*
X1138526Y-162971D01*
X1140273Y-161513D01*
X1141364Y-159763D01*
X1141583Y-158013D01*
X1141146Y-155972D01*
X1139618Y-154513D01*
X1138089Y-153930D01*
X1136124D01*
G01X1138089D02*
X1139399Y-153055D01*
X1140491Y-151597D01*
X1140928Y-149847D01*
X1140491Y-148096D01*
X1139399Y-146638D01*
X1137434Y-145763D01*
X1135469Y-146055D01*
X1133504Y-147222D01*
G01X1026758Y-118263D02*
Y-100763D01*
X1031124D01*
X1032871Y-101638D01*
X1034181Y-102805D01*
X1035273Y-104554D01*
X1036146Y-106597D01*
X1036364Y-109513D01*
X1036146Y-112430D01*
X1035273Y-114472D01*
X1034181Y-116222D01*
X1032871Y-117388D01*
X1031124Y-118263D01*
X1026758D01*
G01X1052991D02*
Y-106597D01*
G01Y-108638D02*
X1052118Y-107472D01*
X1050807Y-106888D01*
X1049279Y-106597D01*
X1047751Y-107180D01*
X1046441Y-108346D01*
X1045567Y-110096D01*
X1045131Y-112430D01*
X1045567Y-114763D01*
X1046441Y-116513D01*
X1047751Y-117680D01*
X1049279Y-118263D01*
X1050807Y-117971D01*
X1052118Y-117097D01*
X1052991Y-115930D01*
G01X1066561Y-100763D02*
Y-118263D01*
G01X1063504Y-106597D02*
X1069618D01*
G01X1080786Y-110388D02*
X1087773D01*
X1087118Y-108346D01*
X1086026Y-107180D01*
X1084498Y-106597D01*
X1082969Y-106888D01*
X1081659Y-107763D01*
X1080786Y-109805D01*
X1080349Y-111555D01*
Y-113305D01*
X1080786Y-115055D01*
X1081878Y-116805D01*
X1083188Y-117971D01*
X1084716Y-118263D01*
X1086244Y-117680D01*
X1087773Y-115930D01*
M02*
